(kicad_pcb
	(version 20241229)
	(generator "pcbnew")
	(generator_version "9.0")
	(general
		(thickness 1.6)
		(legacy_teardrops no)
	)
	(paper "A4")
	(title_block
		(title "OCuLink to PCIe adapter")
		(date "2025-06-18")
		(rev "1.0.0")
		(company "Antmicro Ltd")
		(comment 1 "www.antmicro.com")
		(comment 9 "footprints 115-118 of 159")
	)
	(layers
		(0 "F.Cu" signal)
		(4 "In1.Cu" signal)
		(6 "In2.Cu" signal)
		(2 "B.Cu" signal)
		(9 "F.Adhes" user "F.Adhesive")
		(11 "B.Adhes" user "B.Adhesive")
		(13 "F.Paste" user)
		(15 "B.Paste" user)
		(5 "F.SilkS" user "F.Silkscreen")
		(7 "B.SilkS" user "B.Silkscreen")
		(1 "F.Mask" user)
		(3 "B.Mask" user)
		(17 "Dwgs.User" user "User.Drawings")
		(19 "Cmts.User" user "User.Comments")
		(21 "Eco1.User" user "User.Eco1")
		(23 "Eco2.User" user "User.Eco2")
		(25 "Edge.Cuts" user)
		(27 "Margin" user)
		(31 "F.CrtYd" user "F.Courtyard")
		(29 "B.CrtYd" user "B.Courtyard")
		(35 "F.Fab" user)
		(33 "B.Fab" user)
	)
	(footprint "antmicro-footprints:SOT-23-3"
		(layer "F.Cu")
		(at 140.1005 71.35 90)
		(property "Reference" "Q4"
			(at 2.406999 -1.474 90)
			(layer "F.SilkS")
			(effects
				(font
					(size 0.7 0.7)
					(thickness 0.15)
				)
				(justify right top)
			)
		)
		(property "Value" "BSS138-7-F"
			(at -1.9 2.7 90)
			(layer "F.Fab")
			(effects
				(font
					(size 0.7 0.7)
					(thickness 0.15)
				)
				(justify left bottom)
			)
		)
		(property "Datasheet" "https://www.diodes.com/assets/Datasheets/ds30144.pdf"
			(at 0 0 90)
			(layer "F.Fab")
			(hide yes)
			(effects
				(font
					(size 1.27 1.27)
					(thickness 0.15)
				)
			)
		)
		(property "Description" "Power MOSFET, N Channel, 50 V, 200 mA, 1.4 ohm, SOT-23, Surface Mount"
			(at 0 0 90)
			(layer "F.Fab")
			(hide yes)
			(effects
				(font
					(size 1.27 1.27)
					(thickness 0.15)
				)
			)
		)
		(property "MPN" "BSS138-7-F"
			(at 0 0 90)
			(unlocked yes)
			(layer "F.Fab")
			(hide yes)
			(effects
				(font
					(size 1 1)
					(thickness 0.15)
				)
			)
		)
		(property "Manufacturer" "Diodes Incorporated"
			(at 0 0 90)
			(unlocked yes)
			(layer "F.Fab")
			(hide yes)
			(effects
				(font
					(size 1 1)
					(thickness 0.15)
				)
			)
		)
		(property "Author" "Antmicro"
			(at 0 0 90)
			(unlocked yes)
			(layer "F.Fab")
			(hide yes)
			(effects
				(font
					(size 1 1)
					(thickness 0.15)
				)
			)
		)
		(property "License" "Apache-2.0"
			(at 0 0 90)
			(unlocked yes)
			(layer "F.Fab")
			(hide yes)
			(effects
				(font
					(size 1 1)
					(thickness 0.15)
				)
			)
		)
		(sheetname "/USB-PD/")
		(sheetfile "usb-pd.kicad_sch")
		(attr smd)
		(fp_line
			(start 0.7 -1.5)
			(end -0.7 -1.5)
			(stroke
				(width 0.15)
				(type solid)
			)
			(layer "F.SilkS")
		)
		(fp_line
			(start -0.85 -1.35)
			(end -0.7 -1.5)
			(stroke
				(width 0.15)
				(type solid)
			)
			(layer "F.SilkS")
		)
		(fp_line
			(start -1.45 -1.35)
			(end -0.85 -1.35)
			(stroke
				(width 0.15)
				(type solid)
			)
			(layer "F.SilkS")
		)
		(fp_line
			(start 0.7 -0.4)
			(end 0.7 -1.5)
			(stroke
				(width 0.15)
				(type solid)
			)
			(layer "F.SilkS")
		)
		(fp_line
			(start 0.7 0.4)
			(end 0.7 1.5)
			(stroke
				(width 0.15)
				(type solid)
			)
			(layer "F.SilkS")
		)
		(fp_line
			(start 0.7 1.5)
			(end -0.7 1.5)
			(stroke
				(width 0.15)
				(type solid)
			)
			(layer "F.SilkS")
		)
		(fp_line
			(start -0.7 1.5)
			(end -0.7 1.35)
			(stroke
				(width 0.15)
				(type solid)
			)
			(layer "F.SilkS")
		)
		(fp_line
			(start 0.825 -1.6)
			(end 0.825 -0.45)
			(stroke
				(width 0.05)
				(type solid)
			)
			(layer "F.CrtYd")
		)
		(fp_line
			(start -0.9 -1.6)
			(end 0.825 -1.6)
			(stroke
				(width 0.05)
				(type solid)
			)
			(layer "F.CrtYd")
		)
		(fp_line
			(start -0.9 -1.6)
			(end -0.9 -1.4)
			(stroke
				(width 0.05)
				(type solid)
			)
			(layer "F.CrtYd")
		)
		(fp_line
			(start -0.9 -1.4)
			(end -1.75 -1.4)
			(stroke
				(width 0.05)
				(type solid)
			)
			(layer "F.CrtYd")
		)
		(fp_line
			(start -0.85 -0.5)
			(end -1.75 -0.5)
			(stroke
				(width 0.05)
				(type solid)
			)
			(layer "F.CrtYd")
		)
		(fp_line
			(start -1.75 -0.5)
			(end -1.75 -1.4)
			(stroke
				(width 0.05)
				(type solid)
			)
			(layer "F.CrtYd")
		)
		(fp_line
			(start 1.75 -0.45)
			(end 1.75 0.45)
			(stroke
				(width 0.05)
				(type solid)
			)
			(layer "F.CrtYd")
		)
		(fp_line
			(start 0.825 -0.45)
			(end 1.75 -0.45)
			(stroke
				(width 0.05)
				(type solid)
			)
			(layer "F.CrtYd")
		)
		(fp_line
			(start 1.75 0.45)
			(end 0.85 0.45)
			(stroke
				(width 0.05)
				(type solid)
			)
			(layer "F.CrtYd")
		)
		(fp_line
			(start 0.85 0.45)
			(end 0.85 1.65)
			(stroke
				(width 0.05)
				(type solid)
			)
			(layer "F.CrtYd")
		)
		(fp_line
			(start -0.85 0.5)
			(end -0.85 -0.5)
			(stroke
				(width 0.05)
				(type solid)
			)
			(layer "F.CrtYd")
		)
		(fp_line
			(start -1.75 0.5)
			(end -0.85 0.5)
			(stroke
				(width 0.05)
				(type solid)
			)
			(layer "F.CrtYd")
		)
		(fp_line
			(start -0.85 1.4)
			(end -1.75 1.4)
			(stroke
				(width 0.05)
				(type solid)
			)
			(layer "F.CrtYd")
		)
		(fp_line
			(start -1.75 1.4)
			(end -1.75 0.5)
			(stroke
				(width 0.05)
				(type solid)
			)
			(layer "F.CrtYd")
		)
		(fp_line
			(start 0.85 1.65)
			(end -0.85 1.65)
			(stroke
				(width 0.05)
				(type solid)
			)
			(layer "F.CrtYd")
		)
		(fp_line
			(start -0.85 1.65)
			(end -0.85 1.4)
			(stroke
				(width 0.05)
				(type solid)
			)
			(layer "F.CrtYd")
		)
		(fp_line
			(start -0.437 -1.526)
			(end 0.688 -1.526)
			(stroke
				(width 0.15)
				(type solid)
			)
			(layer "F.Fab")
		)
		(fp_line
			(start -0.437 -1.526)
			(end -0.712 -1.325)
			(stroke
				(width 0.15)
				(type solid)
			)
			(layer "F.Fab")
		)
		(fp_line
			(start -0.712 -1.325)
			(end -0.712 1.523)
			(stroke
				(width 0.15)
				(type solid)
			)
			(layer "F.Fab")
		)
		(fp_line
			(start 0.688 1.519)
			(end 0.688 -1.52)
			(stroke
				(width 0.15)
				(type solid)
			)
			(layer "F.Fab")
		)
		(fp_line
			(start -0.712 1.519)
			(end 0.688 1.519)
			(stroke
				(width 0.15)
				(type solid)
			)
			(layer "F.Fab")
		)
		(fp_text user "${REFERENCE}"
			(at 0 0.025 270)
			(layer "F.Fab")
			(effects
				(font
					(size 0.7 0.7)
					(thickness 0.15)
				)
				(justify right top)
			)
		)
		(fp_text user "Author: Antmicro"
			(at -1.837 5.3 90)
			(layer "F.Fab")
			(effects
				(font
					(size 0.7 0.7)
					(thickness 0.15)
				)
				(justify left bottom)
			)
		)
		(fp_text user "License: Apache-2.0"
			(at -1.8 6.8 90)
			(layer "F.Fab")
			(effects
				(font
					(size 0.7 0.7)
					(thickness 0.15)
				)
				(justify left bottom)
			)
		)
		(pad "1" smd roundrect
			(at -1.1 -0.951 90)
			(size 1 0.6)
			(layers "F.Cu" "F.Mask" "F.Paste")
			(roundrect_rratio 0.15)
			(net 173 "/USB-PD/~{FAULT}")
			(pinfunction "G")
			(pintype "input")
		)
		(pad "2" smd roundrect
			(at -1.1 0.949 90)
			(size 1 0.6)
			(layers "F.Cu" "F.Mask" "F.Paste")
			(roundrect_rratio 0.15)
			(net 66 "GND")
			(pinfunction "S")
			(pintype "passive")
		)
		(pad "3" smd roundrect
			(at 1.1 -0.0005 90)
			(size 1 0.6)
			(layers "F.Cu" "F.Mask" "F.Paste")
			(roundrect_rratio 0.15)
			(net 174 "Net-(Q4-D)")
			(pinfunction "D")
			(pintype "passive")
		)
	)
	(footprint "antmicro-footprints:R_0402_1005Metric"
		(layer "F.Cu")
		(at 151.737 57.376001 90)
		(descr "Resistor SMD 0402")
		(tags "resistor SMD 0402")
		(property "Reference" "R28"
			(at -3.273999 0.439001 90)
			(layer "F.SilkS")
			(effects
				(font
					(size 0.7 0.7)
					(thickness 0.15)
				)
				(justify left bottom)
			)
		)
		(property "Value" "R_1k_0402"
			(at -1.011843 1.772046 90)
			(layer "F.Fab")
			(effects
				(font
					(size 0.7 0.7)
					(thickness 0.15)
				)
				(justify left bottom)
			)
		)
		(property "Datasheet" "https://www.bourns.com/docs/product-datasheets/cr.pdf"
			(at 0 0 90)
			(layer "F.Fab")
			(hide yes)
			(effects
				(font
					(size 1.27 1.27)
					(thickness 0.15)
				)
			)
		)
		(property "Description" "SMD Chip Resistor, 1 kohm, ± 1%, 63 mW, 0402 [1005 Metric], Thick Film, General Purpose"
			(at 0 0 90)
			(layer "F.Fab")
			(hide yes)
			(effects
				(font
					(size 1.27 1.27)
					(thickness 0.15)
				)
			)
		)
		(property "MPN" "CR0402-FX-1001GLF"
			(at 0 0 90)
			(unlocked yes)
			(layer "F.Fab")
			(hide yes)
			(effects
				(font
					(size 1 1)
					(thickness 0.15)
				)
			)
		)
		(property "Manufacturer" "Bourns"
			(at 0 0 90)
			(unlocked yes)
			(layer "F.Fab")
			(hide yes)
			(effects
				(font
					(size 1 1)
					(thickness 0.15)
				)
			)
		)
		(property "License" "Apache-2.0"
			(at 0 0 90)
			(unlocked yes)
			(layer "F.Fab")
			(hide yes)
			(effects
				(font
					(size 1 1)
					(thickness 0.15)
				)
			)
		)
		(property "Author" "Antmicro"
			(at 0 0 90)
			(unlocked yes)
			(layer "F.Fab")
			(hide yes)
			(effects
				(font
					(size 1 1)
					(thickness 0.15)
				)
			)
		)
		(property "Val" "1k"
			(at 0 0 90)
			(unlocked yes)
			(layer "F.Fab")
			(hide yes)
			(effects
				(font
					(size 1 1)
					(thickness 0.15)
				)
			)
		)
		(property "Tolerance" "1%"
			(at 0 0 90)
			(unlocked yes)
			(layer "F.Fab")
			(hide yes)
			(effects
				(font
					(size 1 1)
					(thickness 0.15)
				)
			)
		)
		(sheetname "/USB-PD/")
		(sheetfile "usb-pd.kicad_sch")
		(attr smd exclude_from_bom dnp)
		(fp_rect
			(start -0.925 -0.47)
			(end 0.925 0.47)
			(stroke
				(width 0.05)
				(type default)
			)
			(fill no)
			(layer "F.CrtYd")
		)
		(fp_rect
			(start -0.5 -0.25)
			(end 0.5 0.25)
			(stroke
				(width 0.15)
				(type solid)
			)
			(fill no)
			(layer "F.Fab")
		)
		(fp_text user "Author: Antmicro"
			(at -0.95 4.169 90)
			(layer "F.Fab")
			(effects
				(font
					(size 0.7 0.7)
					(thickness 0.15)
				)
				(justify left bottom)
			)
		)
		(fp_text user "${REFERENCE}"
			(at 0 0 90)
			(layer "F.Fab")
			(effects
				(font
					(size 0.7 0.7)
					(thickness 0.15)
				)
				(justify left bottom)
			)
		)
		(fp_text user "License: Apache-2.0"
			(at -0.949999 5.169 90)
			(layer "F.Fab")
			(effects
				(font
					(size 0.7 0.7)
					(thickness 0.15)
				)
				(justify left bottom)
			)
		)
		(pad "1" smd roundrect
			(at -0.48 0 90)
			(size 0.59 0.64)
			(layers "F.Cu" "F.Mask" "F.Paste")
			(roundrect_rratio 0.25)
			(net 66 "GND")
			(pintype "passive")
		)
		(pad "2" smd roundrect
			(at 0.48 0 90)
			(size 0.59 0.64)
			(layers "F.Cu" "F.Mask" "F.Paste")
			(roundrect_rratio 0.25)
			(net 138 "/USB-PD/ISNK_COARSE")
			(pintype "passive")
		)
	)
	(footprint "antmicro-footprints:C_0402_1005Metric"
		(layer "F.Cu")
		(at 148.151999 90 180)
		(descr "Capacitor SMD 0402")
		(tags "capacitor SMD 0402")
		(property "Reference" "C20"
			(at -3.448001 0.5 180)
			(layer "F.SilkS")
			(effects
				(font
					(size 0.7 0.7)
					(thickness 0.15)
				)
				(justify right top)
			)
		)
		(property "Value" "C_1u_25V_0402"
			(at -1.022927 2.155213 0)
			(layer "F.Fab")
			(effects
				(font
					(size 0.7 0.7)
					(thickness 0.15)
				)
				(justify right top)
			)
		)
		(property "Datasheet" "https://www.murata.com/products/productdetail?partno=GRM155R61E105KE11%23"
			(at 0 0 0)
			(layer "F.Fab")
			(hide yes)
			(effects
				(font
					(size 1.27 1.27)
					(thickness 0.15)
				)
			)
		)
		(property "Description" "SMD Multilayer Ceramic Capacitor, 1 µF, 25 V, 0402 [1005 Metric], ± 10%, X5R, GRM Series"
			(at 0 0 0)
			(layer "F.Fab")
			(hide yes)
			(effects
				(font
					(size 1.27 1.27)
					(thickness 0.15)
				)
			)
		)
		(property "MPN" "GRM155R61E105KE11J"
			(at 0 0 180)
			(unlocked yes)
			(layer "F.Fab")
			(hide yes)
			(effects
				(font
					(size 1 1)
					(thickness 0.15)
				)
			)
		)
		(property "Manufacturer" "Murata"
			(at 0 0 180)
			(unlocked yes)
			(layer "F.Fab")
			(hide yes)
			(effects
				(font
					(size 1 1)
					(thickness 0.15)
				)
			)
		)
		(property "License" "Apache-2.0"
			(at 0 0 180)
			(unlocked yes)
			(layer "F.Fab")
			(hide yes)
			(effects
				(font
					(size 1 1)
					(thickness 0.15)
				)
			)
		)
		(property "Author" "Antmicro"
			(at 0 0 180)
			(unlocked yes)
			(layer "F.Fab")
			(hide yes)
			(effects
				(font
					(size 1 1)
					(thickness 0.15)
				)
			)
		)
		(property "Val" "1u"
			(at 0 0 180)
			(unlocked yes)
			(layer "F.Fab")
			(hide yes)
			(effects
				(font
					(size 1 1)
					(thickness 0.15)
				)
			)
		)
		(property "Voltage" "25V"
			(at 0 0 180)
			(unlocked yes)
			(layer "F.Fab")
			(hide yes)
			(effects
				(font
					(size 1 1)
					(thickness 0.15)
				)
			)
		)
		(property "Dielectric" "X5R"
			(at 0 0 180)
			(unlocked yes)
			(layer "F.Fab")
			(hide yes)
			(effects
				(font
					(size 1 1)
					(thickness 0.15)
				)
			)
		)
		(sheetname "/USB-PD/")
		(sheetfile "usb-pd.kicad_sch")
		(attr smd)
		(fp_rect
			(start -0.925 -0.47)
			(end 0.925 0.47)
			(stroke
				(width 0.05)
				(type default)
			)
			(fill no)
			(layer "F.CrtYd")
		)
		(fp_line
			(start 0.504 0.248)
			(end -0.494 0.248)
			(stroke
				(width 0.15)
				(type solid)
			)
			(layer "F.Fab")
		)
		(fp_line
			(start 0.504 -0.25)
			(end 0.504 0.248)
			(stroke
				(width 0.15)
				(type solid)
			)
			(layer "F.Fab")
		)
		(fp_line
			(start -0.494 0.248)
			(end -0.494 -0.25)
			(stroke
				(width 0.15)
				(type solid)
			)
			(layer "F.Fab")
		)
		(fp_line
			(start -0.494 -0.25)
			(end 0.504 -0.25)
			(stroke
				(width 0.15)
				(type solid)
			)
			(layer "F.Fab")
		)
		(fp_text user "License: Apache-2.0"
			(at -0.939 5.799 0)
			(layer "F.Fab")
			(effects
				(font
					(size 0.7 0.7)
					(thickness 0.15)
				)
				(justify right top)
			)
		)
		(fp_text user "Author: Antmicro"
			(at -0.939 3.399 0)
			(layer "F.Fab")
			(effects
				(font
					(size 0.7 0.7)
					(thickness 0.15)
				)
				(justify right top)
			)
		)
		(fp_text user "${REFERENCE}"
			(at 0 0 0)
			(layer "F.Fab")
			(effects
				(font
					(size 0.7 0.7)
					(thickness 0.15)
				)
				(justify right top)
			)
		)
		(pad "1" smd roundrect
			(at -0.48 0 180)
			(size 0.59 0.64)
			(layers "F.Cu" "F.Mask" "F.Paste")
			(roundrect_rratio 0.25)
			(net 66 "GND")
			(pintype "passive")
		)
		(pad "2" smd roundrect
			(at 0.48 0 180)
			(size 0.59 0.64)
			(layers "F.Cu" "F.Mask" "F.Paste")
			(roundrect_rratio 0.25)
			(net 121 "/USB-PD/12V_VDD")
			(pintype "passive")
		)
	)
	(footprint "antmicro-footprints:C_0805_2012Metric"
		(layer "F.Cu")
		(at 138.2 93.5 -90)
		(descr "Capacitor SMD 0805")
		(tags "capacitor SMD 0805")
		(property "Reference" "C16"
			(at -2.5 5.6 90)
			(layer "F.SilkS")
			(effects
				(font
					(size 0.7 0.7)
					(thickness 0.15)
				)
				(justify right top)
			)
		)
		(property "Value" "C_22u_25V_0805"
			(at -2.055717 1.963153 90)
			(layer "F.Fab")
			(effects
				(font
					(size 0.7 0.7)
					(thickness 0.15)
				)
				(justify right top)
			)
		)
		(property "Datasheet" "https://product.samsungsem.com/mlcc/CL21A226MAYNNN.do"
			(at 0 0 90)
			(layer "F.Fab")
			(hide yes)
			(effects
				(font
					(size 1.27 1.27)
					(thickness 0.15)
				)
			)
		)
		(property "Description" "SMT Multilayer Ceramic Capacitor, 22uF, +/-20%, 25V, X5R, 0805 [2012 Metric]"
			(at 0 0 90)
			(layer "F.Fab")
			(hide yes)
			(effects
				(font
					(size 1.27 1.27)
					(thickness 0.15)
				)
			)
		)
		(property "MPN" "CL21A226MAYNNNE"
			(at 0 0 270)
			(unlocked yes)
			(layer "F.Fab")
			(hide yes)
			(effects
				(font
					(size 1 1)
					(thickness 0.15)
				)
			)
		)
		(property "Manufacturer" "Samsung Electro-Mechanics"
			(at 0 0 270)
			(unlocked yes)
			(layer "F.Fab")
			(hide yes)
			(effects
				(font
					(size 1 1)
					(thickness 0.15)
				)
			)
		)
		(property "License" "Apache-2.0"
			(at 0 0 270)
			(unlocked yes)
			(layer "F.Fab")
			(hide yes)
			(effects
				(font
					(size 1 1)
					(thickness 0.15)
				)
			)
		)
		(property "Author" "Antmicro"
			(at 0 0 270)
			(unlocked yes)
			(layer "F.Fab")
			(hide yes)
			(effects
				(font
					(size 1 1)
					(thickness 0.15)
				)
			)
		)
		(property "Val" "22u"
			(at 0 0 270)
			(unlocked yes)
			(layer "F.Fab")
			(hide yes)
			(effects
				(font
					(size 1 1)
					(thickness 0.15)
				)
			)
		)
		(property "Voltage" "25V"
			(at 0 0 270)
			(unlocked yes)
			(layer "F.Fab")
			(hide yes)
			(effects
				(font
					(size 1 1)
					(thickness 0.15)
				)
			)
		)
		(property "Dielectric" "X5R"
			(at 0 0 270)
			(unlocked yes)
			(layer "F.Fab")
			(hide yes)
			(effects
				(font
					(size 1 1)
					(thickness 0.15)
				)
			)
		)
		(property "Public" "False"
			(at 0 0 270)
			(unlocked yes)
			(layer "F.Fab")
			(hide yes)
			(effects
				(font
					(size 1 1)
					(thickness 0.15)
				)
			)
		)
		(sheetname "/USB-PD/")
		(sheetfile "usb-pd.kicad_sch")
		(attr smd)
		(fp_line
			(start -0.3 0.7)
			(end 0.3 0.7)
			(stroke
				(width 0.15)
				(type solid)
			)
			(layer "F.SilkS")
		)
		(fp_line
			(start -0.3 -0.7)
			(end 0.3 -0.7)
			(stroke
				(width 0.15)
				(type solid)
			)
			(layer "F.SilkS")
		)
		(fp_rect
			(start 1.95 -0.9)
			(end -1.95 0.9)
			(stroke
				(width 0.05)
				(type default)
			)
			(fill no)
			(layer "F.CrtYd")
		)
		(fp_rect
			(start -0.95 -0.675)
			(end 0.95 0.675)
			(stroke
				(width 0.15)
				(type solid)
			)
			(fill no)
			(layer "F.Fab")
		)
		(fp_text user "License: Apache-2.0"
			(at -1.9 4.947 90)
			(layer "F.Fab")
			(effects
				(font
					(size 0.7 0.7)
					(thickness 0.15)
				)
				(justify right top)
			)
		)
		(fp_text user "Author: Antmicro"
			(at -1.9 5.947 90)
			(layer "F.Fab")
			(effects
				(font
					(size 0.7 0.7)
					(thickness 0.15)
				)
				(justify right top)
			)
		)
		(fp_text user "${REFERENCE}"
			(at 0 0 90)
			(layer "F.Fab")
			(effects
				(font
					(size 0.7 0.7)
					(thickness 0.15)
				)
				(justify right top)
			)
		)
		(pad "1" smd roundrect
			(at -1.1 0 270)
			(size 1.2 1.3)
			(layers "F.Cu" "F.Mask" "F.Paste")
			(roundrect_rratio 0.25)
			(net 66 "GND")
			(pintype "passive")
		)
		(pad "2" smd roundrect
			(at 1.1 0 270)
			(size 1.2 1.3)
			(layers "F.Cu" "F.Mask" "F.Paste")
			(roundrect_rratio 0.25)
			(net 187 "/USB-PD/12V_CONV")
			(pintype "passive")
		)
	)
)
